(kicad_pcb
	(version 20260206)
	(generator "pcbnew")
	(generator_version "10.0")
	(general
		(thickness 1.6)
		(legacy_teardrops no)
	)
	(paper "A4")
	(title_block
		(title "panther-plus-userver — 13130-1b_20150205.brd")
		(comment 1 "Honey Badger (Wiwynn) / footprints 426-434 of 1509")
	)
	(layers
		(0 "F.Cu" signal "TOP")
		(4 "In1.Cu" signal "L2")
		(6 "In2.Cu" signal "L3")
		(8 "In3.Cu" signal "L4")
		(10 "In4.Cu" signal "L5")
		(12 "In5.Cu" signal "L6")
		(14 "In6.Cu" signal "L7")
		(16 "In7.Cu" signal "L8")
		(18 "In8.Cu" signal "L9")
		(20 "In9.Cu" signal "L10")
		(22 "In10.Cu" signal "L11")
		(2 "B.Cu" signal "BOTTOM")
		(9 "F.Adhes" user "F.Adhesive")
		(11 "B.Adhes" user "B.Adhesive")
		(13 "F.Paste" user "Package Geometry/Pastemask Top")
		(15 "B.Paste" user "Package Geometry/Pastemask Bottom")
		(5 "F.SilkS" user "Ref Des/Silkscreen Top")
		(7 "B.SilkS" user "Ref Des/Silkscreen Bottom")
		(1 "F.Mask" user "Board Geometry/Soldermask Top")
		(3 "B.Mask" user "Board Geometry/Soldermask Bottom")
		(17 "Dwgs.User" user "User.Drawings")
		(19 "Cmts.User" user "User.Comments")
		(21 "Eco1.User" user "User.Eco1")
		(23 "Eco2.User" user "User.Eco2")
		(25 "Edge.Cuts" user "Board Geometry/Outline")
		(27 "Margin" user)
		(31 "F.CrtYd" user "Package Geometry/Place Bound Top")
		(29 "B.CrtYd" user "Package Geometry/Place Bound Bottom")
		(35 "F.Fab" user "Ref Des/Assembly Top")
		(33 "B.Fab" user "Ref Des/Assembly Bottom")
	)
	(footprint ""
		(layer "F.Cu")
		(at 139.7 -21.717)
		(property "Reference" "TP13"
			(at 0 0 0)
			(layer "F.SilkS")
			(hide yes)
			(effects
				(font
					(size 1.27 1.27)
				)
			)
		)
		(property "Value" "TPAD28-1-GP-U"
			(at 0.0508 -1.9304 0)
			(unlocked yes)
			(layer "F.Fab")
			(hide yes)
			(effects
				(font
					(size 1.016 1.016)
					(thickness 0.1524)
				)
			)
		)
		(property "Device Type" "TPAD28-1-U"
			(at 0.0508 -3.4544 0)
			(unlocked yes)
			(layer "F.Fab")
			(hide yes)
			(effects
				(font
					(size 1.016 1.016)
					(thickness 0.1524)
				)
			)
		)
		(duplicate_pad_numbers_are_jumpers no)
		(fp_poly
			(pts
				(arc
					(start 0.3556 0)
					(mid -0.3556 0)
					(end 0.3556 0)
				)
			)
			(stroke
				(width 0)
				(type default)
			)
			(fill no)
			(layer "F.CrtYd")
		)
		(fp_poly
			(pts
				(arc
					(start 0.9525 0)
					(mid -0.9525 0)
					(end 0.9525 0)
				)
			)
			(stroke
				(width 0)
				(type default)
			)
			(fill no)
			(layer "F.Fab")
		)
		(pad "1" smd circle
			(at 0 0)
			(size 0.7112 0.7112)
			(layers "F.Cu" "F.Mask" "F.Paste")
			(net "TP_FPGA_P85")
		)
	)
	(footprint ""
		(layer "F.Cu")
		(at 204.7748 -23.114 90)
		(property "Reference" "TP15"
			(at 0 0 90)
			(layer "F.SilkS")
			(hide yes)
			(effects
				(font
					(size 1.27 1.27)
				)
			)
		)
		(property "Value" "TPAD32-GP"
			(at 0 -3.166364 90)
			(unlocked yes)
			(layer "F.Fab")
			(hide yes)
			(effects
				(font
					(size 1.016 1.016)
					(thickness 0.1524)
				)
			)
		)
		(property "Device Type" "TPAD32"
			(at 0 -4.690618 90)
			(unlocked yes)
			(layer "F.Fab")
			(hide yes)
			(effects
				(font
					(size 1.016 1.016)
					(thickness 0.1524)
				)
			)
		)
		(duplicate_pad_numbers_are_jumpers no)
		(fp_poly
			(pts
				(arc
					(start 0 0.7112)
					(mid 0 -0.7112)
					(end 0 0.7112)
				)
			)
			(stroke
				(width 0)
				(type default)
			)
			(fill no)
			(layer "F.CrtYd")
		)
		(fp_poly
			(pts
				(arc
					(start 0 0.7112)
					(mid 0 -0.7112)
					(end 0 0.7112)
				)
			)
			(stroke
				(width 0)
				(type default)
			)
			(fill no)
			(layer "F.Fab")
		)
		(pad "1" smd circle
			(at 0 0 90)
			(size 0.8128 0.8128)
			(layers "F.Cu" "F.Mask" "F.Paste")
			(net "JTAG_PLD_TMS")
		)
	)
	(footprint ""
		(layer "F.Cu")
		(at 6.7818 -51.7652 -90)
		(property "Reference" "R7"
			(at 0 0 270)
			(layer "F.SilkS")
			(hide yes)
			(effects
				(font
					(size 1.27 1.27)
				)
			)
		)
		(property "Value" "4K7R2F-GP"
			(at 0.064008 -3.993896 270)
			(unlocked yes)
			(layer "F.Fab")
			(hide yes)
			(effects
				(font
					(size 1.016 1.016)
					(thickness 0.1524)
				)
			)
		)
		(property "Device Type" "R402H16"
			(at 0.064008 -5.517896 270)
			(unlocked yes)
			(layer "F.Fab")
			(hide yes)
			(effects
				(font
					(size 1.016 1.016)
					(thickness 0.1524)
				)
			)
		)
		(duplicate_pad_numbers_are_jumpers no)
		(fp_rect
			(start -0.381 0.8382)
			(end 0.381 -0.8382)
			(stroke
				(width 0)
				(type default)
			)
			(fill no)
			(layer "F.CrtYd")
		)
		(fp_rect
			(start -0.381 0.8382)
			(end 0.381 -0.8382)
			(stroke
				(width 0)
				(type default)
			)
			(fill no)
			(layer "F.Fab")
		)
		(pad "1" smd custom
			(at 0 -0.4318 270)
			(size 0.127 0.127)
			(layers "F.Cu" "F.Mask" "F.Paste")
			(net "TEMP_1_A1")
			(options
				(clearance outline)
				(anchor circle)
			)
			(primitives
				(gr_poly
					(pts
						(arc
							(start -0.2032 -0.2794)
							(mid -0.239121 -0.264521)
							(end -0.254 -0.2286)
						)
						(arc
							(start -0.254 0.2286)
							(mid -0.239121 0.264521)
							(end -0.2032 0.2794)
						)
						(arc
							(start 0.2032 0.2794)
							(mid 0.239121 0.264521)
							(end 0.254 0.2286)
						)
						(arc
							(start 0.254 -0.2286)
							(mid 0.239121 -0.264521)
							(end 0.2032 -0.2794)
						)
					)
					(width 0)
					(fill yes)
				)
			)
		)
		(pad "2" smd custom
			(at 0 0.4318 270)
			(size 0.127 0.127)
			(layers "F.Cu" "F.Mask" "F.Paste")
			(net "GND")
			(options
				(clearance outline)
				(anchor circle)
			)
			(primitives
				(gr_poly
					(pts
						(arc
							(start -0.2032 -0.2794)
							(mid -0.239121 -0.264521)
							(end -0.254 -0.2286)
						)
						(arc
							(start -0.254 0.2286)
							(mid -0.239121 0.264521)
							(end -0.2032 0.2794)
						)
						(arc
							(start 0.2032 0.2794)
							(mid 0.239121 0.264521)
							(end 0.254 0.2286)
						)
						(arc
							(start 0.254 -0.2286)
							(mid 0.239121 -0.264521)
							(end 0.2032 -0.2794)
						)
					)
					(width 0)
					(fill yes)
				)
			)
		)
	)
	(footprint ""
		(layer "F.Cu")
		(at 8.509 -60.071 90)
		(property "Reference" "C37"
			(at 0 0 90)
			(layer "F.SilkS")
			(hide yes)
			(effects
				(font
					(size 1.27 1.27)
				)
			)
		)
		(property "Value" "SCD1U16V2KX-3GP"
			(at 1.1811 -2.7051 90)
			(unlocked yes)
			(layer "F.Fab")
			(hide yes)
			(effects
				(font
					(size 1.016 1.016)
					(thickness 0.1524)
				)
			)
		)
		(property "Device Type" "C402H22"
			(at 1.1811 -4.2291 90)
			(unlocked yes)
			(layer "F.Fab")
			(hide yes)
			(effects
				(font
					(size 1.016 1.016)
					(thickness 0.1524)
				)
			)
		)
		(duplicate_pad_numbers_are_jumpers no)
		(fp_rect
			(start -0.381 0.7366)
			(end 0.381 -0.7366)
			(stroke
				(width 0)
				(type default)
			)
			(fill no)
			(layer "F.CrtYd")
		)
		(fp_rect
			(start -0.381 0.7366)
			(end 0.381 -0.7366)
			(stroke
				(width 0)
				(type default)
			)
			(fill no)
			(layer "F.Fab")
		)
		(pad "1" smd custom
			(at 0 -0.4572 90)
			(size 0.1143 0.1143)
			(layers "F.Cu" "F.Mask" "F.Paste")
			(net "P2E_CPU_NGFF_TX_DN14")
			(options
				(clearance outline)
				(anchor circle)
			)
			(primitives
				(gr_poly
					(pts
						(arc
							(start -0.254 -0.1778)
							(mid -0.239121 -0.213721)
							(end -0.2032 -0.2286)
						)
						(arc
							(start 0.2032 -0.2286)
							(mid 0.239121 -0.213721)
							(end 0.254 -0.1778)
						)
						(arc
							(start 0.254 0.1778)
							(mid 0.239121 0.213721)
							(end 0.2032 0.2286)
						)
						(arc
							(start -0.2032 0.2286)
							(mid -0.239121 0.213721)
							(end -0.254 0.1778)
						)
					)
					(width 0)
					(fill yes)
				)
			)
		)
		(pad "2" smd custom
			(at 0 0.4572 90)
			(size 0.1143 0.1143)
			(layers "F.Cu" "F.Mask" "F.Paste")
			(net "P2E_CPU_NGFF_C_TX_DN14")
			(options
				(clearance outline)
				(anchor circle)
			)
			(primitives
				(gr_poly
					(pts
						(arc
							(start -0.254 -0.1778)
							(mid -0.239121 -0.213721)
							(end -0.2032 -0.2286)
						)
						(arc
							(start 0.2032 -0.2286)
							(mid 0.239121 -0.213721)
							(end 0.254 -0.1778)
						)
						(arc
							(start 0.254 0.1778)
							(mid 0.239121 0.213721)
							(end 0.2032 0.2286)
						)
						(arc
							(start -0.2032 0.2286)
							(mid -0.239121 0.213721)
							(end -0.254 0.1778)
						)
					)
					(width 0)
					(fill yes)
				)
			)
		)
	)
	(footprint ""
		(layer "F.Cu")
		(at 18.4404 -64.1604 -90)
		(property "Reference" "PC22"
			(at 0 0 270)
			(layer "F.SilkS")
			(hide yes)
			(effects
				(font
					(size 1.27 1.27)
				)
			)
		)
		(property "Value" "SC1KP50V2KX-1GP"
			(at 1.8923 -1.2065 270)
			(unlocked yes)
			(layer "F.Fab")
			(hide yes)
			(effects
				(font
					(size 1.016 1.016)
					(thickness 0.1524)
				)
			)
		)
		(property "Device Type" "C402H22"
			(at 1.8923 -2.7305 270)
			(unlocked yes)
			(layer "F.Fab")
			(hide yes)
			(effects
				(font
					(size 1.016 1.016)
					(thickness 0.1524)
				)
			)
		)
		(duplicate_pad_numbers_are_jumpers no)
		(fp_rect
			(start -0.381 0.7366)
			(end 0.381 -0.7366)
			(stroke
				(width 0)
				(type default)
			)
			(fill no)
			(layer "F.CrtYd")
		)
		(fp_rect
			(start -0.381 0.7366)
			(end 0.381 -0.7366)
			(stroke
				(width 0)
				(type default)
			)
			(fill no)
			(layer "F.Fab")
		)
		(pad "1" smd custom
			(at 0 -0.4572 270)
			(size 0.1143 0.1143)
			(layers "F.Cu" "F.Mask" "F.Paste")
			(net "VR_PVNN_COMP")
			(options
				(clearance outline)
				(anchor circle)
			)
			(primitives
				(gr_poly
					(pts
						(arc
							(start -0.254 -0.1778)
							(mid -0.239121 -0.213721)
							(end -0.2032 -0.2286)
						)
						(arc
							(start 0.2032 -0.2286)
							(mid 0.239121 -0.213721)
							(end 0.254 -0.1778)
						)
						(arc
							(start 0.254 0.1778)
							(mid 0.239121 0.213721)
							(end 0.2032 0.2286)
						)
						(arc
							(start -0.2032 0.2286)
							(mid -0.239121 0.213721)
							(end -0.254 0.1778)
						)
					)
					(width 0)
					(fill yes)
				)
			)
		)
		(pad "2" smd custom
			(at 0 0.4572 270)
			(size 0.1143 0.1143)
			(layers "F.Cu" "F.Mask" "F.Paste")
			(net "VR_PVNN_VW")
			(options
				(clearance outline)
				(anchor circle)
			)
			(primitives
				(gr_poly
					(pts
						(arc
							(start -0.254 -0.1778)
							(mid -0.239121 -0.213721)
							(end -0.2032 -0.2286)
						)
						(arc
							(start 0.2032 -0.2286)
							(mid 0.239121 -0.213721)
							(end 0.254 -0.1778)
						)
						(arc
							(start 0.254 0.1778)
							(mid 0.239121 0.213721)
							(end 0.2032 0.2286)
						)
						(arc
							(start -0.2032 0.2286)
							(mid -0.239121 0.213721)
							(end -0.254 0.1778)
						)
					)
					(width 0)
					(fill yes)
				)
			)
		)
	)
	(footprint ""
		(layer "F.Cu")
		(at 62.484 -48.641 180)
		(property "Reference" "R35"
			(at 0 0 180)
			(layer "F.SilkS")
			(hide yes)
			(effects
				(font
					(size 1.27 1.27)
				)
			)
		)
		(property "Value" "0R2J-2-GP"
			(at 0.064008 -3.993896 180)
			(unlocked yes)
			(layer "F.Fab")
			(hide yes)
			(effects
				(font
					(size 1.016 1.016)
					(thickness 0.1524)
				)
			)
		)
		(property "Device Type" "R402H16"
			(at 0.064008 -5.517896 180)
			(unlocked yes)
			(layer "F.Fab")
			(hide yes)
			(effects
				(font
					(size 1.016 1.016)
					(thickness 0.1524)
				)
			)
		)
		(duplicate_pad_numbers_are_jumpers no)
		(fp_rect
			(start -0.381 0.8382)
			(end 0.381 -0.8382)
			(stroke
				(width 0)
				(type default)
			)
			(fill no)
			(layer "F.CrtYd")
		)
		(fp_rect
			(start -0.381 0.8382)
			(end 0.381 -0.8382)
			(stroke
				(width 0)
				(type default)
			)
			(fill no)
			(layer "F.Fab")
		)
		(pad "1" smd custom
			(at 0 -0.4318 180)
			(size 0.127 0.127)
			(layers "F.Cu" "F.Mask" "F.Paste")
			(net "SMB_HOST_LV_R_CLK")
			(options
				(clearance outline)
				(anchor circle)
			)
			(primitives
				(gr_poly
					(pts
						(arc
							(start -0.2032 -0.2794)
							(mid -0.239121 -0.264521)
							(end -0.254 -0.2286)
						)
						(arc
							(start -0.254 0.2286)
							(mid -0.239121 0.264521)
							(end -0.2032 0.2794)
						)
						(arc
							(start 0.2032 0.2794)
							(mid 0.239121 0.264521)
							(end 0.254 0.2286)
						)
						(arc
							(start 0.254 -0.2286)
							(mid 0.239121 -0.264521)
							(end 0.2032 -0.2794)
						)
					)
					(width 0)
					(fill yes)
				)
			)
		)
		(pad "2" smd custom
			(at 0 0.4318 180)
			(size 0.127 0.127)
			(layers "F.Cu" "F.Mask" "F.Paste")
			(net "SMB_HOST_LV_CLK")
			(options
				(clearance outline)
				(anchor circle)
			)
			(primitives
				(gr_poly
					(pts
						(arc
							(start -0.2032 -0.2794)
							(mid -0.239121 -0.264521)
							(end -0.254 -0.2286)
						)
						(arc
							(start -0.254 0.2286)
							(mid -0.239121 0.264521)
							(end -0.2032 0.2794)
						)
						(arc
							(start 0.2032 0.2794)
							(mid 0.239121 0.264521)
							(end 0.254 0.2286)
						)
						(arc
							(start 0.254 -0.2286)
							(mid 0.239121 -0.264521)
							(end 0.2032 -0.2794)
						)
					)
					(width 0)
					(fill yes)
				)
			)
		)
	)
	(footprint ""
		(layer "F.Cu")
		(at 48.768 -65.151)
		(property "Reference" "PC28"
			(at 0 0 0)
			(layer "F.SilkS")
			(hide yes)
			(effects
				(font
					(size 1.27 1.27)
				)
			)
		)
		(property "Value" "SC47U6D3V5MX-1-GP"
			(at 0 -4.9022 0)
			(unlocked yes)
			(layer "F.Fab")
			(hide yes)
			(effects
				(font
					(size 1.016 1.016)
					(thickness 0.1524)
				)
			)
		)
		(property "Device Type" "C805H54"
			(at 0 -6.8072 0)
			(unlocked yes)
			(layer "F.Fab")
			(hide yes)
			(effects
				(font
					(size 1.016 1.016)
					(thickness 0.1524)
				)
			)
		)
		(duplicate_pad_numbers_are_jumpers no)
		(fp_line
			(start 0.6096 0)
			(end -0.6096 0)
			(stroke
				(width 0.3048)
				(type default)
			)
			(layer "F.SilkS")
		)
		(fp_poly
			(pts
				(xy -0.9017 1.4351) (xy 0.9017 1.4351) (xy 0.9017 -1.4351) (xy -0.9017 -1.4351)
			)
			(stroke
				(width 0)
				(type default)
			)
			(fill no)
			(layer "F.CrtYd")
		)
		(fp_poly
			(pts
				(xy 0.9017 1.4351) (xy 0.9017 -1.4351) (xy -0.9017 -1.4351) (xy -0.9017 1.4351)
			)
			(stroke
				(width 0)
				(type default)
			)
			(fill no)
			(layer "F.Fab")
		)
		(pad "1" smd rect
			(at 0 -0.8382)
			(size 1.5494 0.9398)
			(layers "F.Cu" "F.Mask" "F.Paste")
			(net "PVNN")
		)
		(pad "2" smd rect
			(at 0 0.8382)
			(size 1.5494 0.9398)
			(layers "F.Cu" "F.Mask" "F.Paste")
			(net "GND")
		)
	)
	(footprint ""
		(layer "F.Cu")
		(at 166.37 -46.355 -90)
		(property "Reference" "U24"
			(at 0 0 270)
			(layer "F.SilkS")
			(hide yes)
			(effects
				(font
					(size 1.27 1.27)
				)
			)
		)
		(property "Value" "2N7002DW-7F-GP"
			(at -2.5654 1.1049 270)
			(unlocked yes)
			(layer "F.Fab")
			(hide yes)
			(effects
				(font
					(size 1.016 1.016)
					(thickness 0.1524)
				)
			)
		)
		(property "Device Type" "SOT-363H44"
			(at -2.5654 -0.4191 270)
			(unlocked yes)
			(layer "F.Fab")
			(hide yes)
			(effects
				(font
					(size 1.016 1.016)
					(thickness 0.1524)
				)
			)
		)
		(duplicate_pad_numbers_are_jumpers no)
		(fp_poly
			(pts
				(xy -0.6731 1.4351) (xy -0.9779 1.7399) (xy -0.381 1.7399) (xy -0.3683 1.7399) (xy -0.381 1.7272)
			)
			(stroke
				(width 0)
				(type default)
			)
			(fill yes)
			(layer "F.SilkS")
		)
		(fp_poly
			(pts
				(xy 1.2573 0.8763) (xy 1.2573 -0.8763) (xy 0.9525 -0.8763) (xy 0.9525 -1.4351) (xy -0.9525 -1.4351)
				(xy -0.9525 -0.8763) (xy -1.2573 -0.8763) (xy -1.2573 0.8763) (xy -0.9525 0.8763) (xy -0.9525 1.4351)
				(xy 0.9525 1.4351) (xy 0.9525 0.8763)
			)
			(stroke
				(width 0)
				(type default)
			)
			(fill no)
			(layer "F.CrtYd")
		)
		(fp_poly
			(pts
				(xy 1.2573 0.8763) (xy 1.2573 -0.8763) (xy 0.9525 -0.8763) (xy 0.9525 -1.4351) (xy -0.9525 -1.4351)
				(xy -0.9525 -0.8763) (xy -1.2573 -0.8763) (xy -1.2573 0.8763) (xy -0.9525 0.8763) (xy -0.9525 1.4351)
				(xy 0.9525 1.4351) (xy 0.9525 0.8763)
			)
			(stroke
				(width 0)
				(type default)
			)
			(fill no)
			(layer "F.Fab")
		)
		(pad "1" smd rect
			(at -0.65024 0.8255 270)
			(size 0.3556 0.9652)
			(layers "F.Cu" "F.Mask" "F.Paste")
			(net "XDP_SOC_CPU_TRST#_S")
		)
		(pad "2" smd rect
			(at 0 0.8255 270)
			(size 0.3556 0.9652)
			(layers "F.Cu" "F.Mask" "F.Paste")
			(net "JTAG_CHAIN_EN")
		)
		(pad "3" smd rect
			(at 0.65024 0.8255 270)
			(size 0.3556 0.9652)
			(layers "F.Cu" "F.Mask" "F.Paste")
			(net "JTAG_PLD_TDO_D")
		)
		(pad "4" smd rect
			(at 0.65024 -0.8255 270)
			(size 0.3556 0.9652)
			(layers "F.Cu" "F.Mask" "F.Paste")
			(net "XDP_SOC_CPU_TDI_S")
		)
		(pad "5" smd rect
			(at 0 -0.8255 270)
			(size 0.3556 0.9652)
			(layers "F.Cu" "F.Mask" "F.Paste")
			(net "JTAG_CHAIN_EN")
		)
		(pad "6" smd rect
			(at -0.65024 -0.8255 270)
			(size 0.3556 0.9652)
			(layers "F.Cu" "F.Mask" "F.Paste")
			(net "JTAG_RST_D#")
		)
	)
	(footprint ""
		(layer "F.Cu")
		(at 201.3712 -46.7614 -90)
		(property "Reference" "PG3"
			(at 0 0 270)
			(layer "F.SilkS")
			(hide yes)
			(effects
				(font
					(size 1.27 1.27)
				)
			)
		)
		(property "Value" "GAP-CLOSE-PWR-4-GP"
			(at -2.4638 -0.5461 270)
			(unlocked yes)
			(layer "F.Fab")
			(hide yes)
			(effects
				(font
					(size 1.016 1.016)
					(thickness 0.1524)
				)
			)
		)
		(property "Device Type" "GAP-CLOSE-PWR-4"
			(at -2.4638 -2.0701 270)
			(unlocked yes)
			(layer "F.Fab")
			(hide yes)
			(effects
				(font
					(size 1.016 1.016)
					(thickness 0.1524)
				)
			)
		)
		(duplicate_pad_numbers_are_jumpers no)
		(fp_rect
			(start -0.2794 0.254)
			(end 0.2794 -0.254)
			(stroke
				(width 0)
				(type default)
			)
			(fill no)
			(layer "F.CrtYd")
		)
		(fp_rect
			(start -0.2794 0.254)
			(end 0.2794 -0.254)
			(stroke
				(width 0)
				(type default)
			)
			(fill no)
			(layer "F.Fab")
		)
		(pad "1" smd rect
			(at -0.0635 0 270)
			(size 0.1778 0.254)
			(layers "F.Cu" "F.Mask" "F.Paste")
			(net "PV_VDDR")
		)
		(pad "2" smd rect
			(at 0.0635 0 270)
			(size 0.1778 0.254)
			(layers "F.Cu" "F.Mask" "F.Paste")
			(net "VR_PVDDRA_R_ISUMN1")
		)
	)
)
